# TIMECARD (Time Appliance Project (Time Card)) — schematic netlist excerpt (pin names and nets, part order shuffled) for the footprints in the layout excerpt that follows; sources: Cadence DE-HDL packaged netlist, KiCad conversion of R4006-B0001-02_R01.brd

R377  RESISTOR  4.7KOHM 1%  pkg SMC_0402R_H016  page 23 : \1\ = XP3R3V_FPGA ; \2\ = SMA3_SIG_IN_BF_EN_N
C253  CAPACITOR  0.1UF 10V 10%  pkg SMC_0402R_H022  page 15 : \1\ = OSC_125M_CLKP ; \2\ = MHZ125CLKP_CLKIN

(kicad_pcb
	(version 20260206)
	(generator "pcbnew")
	(generator_version "10.0")
	(general
		(thickness 1.6)
		(legacy_teardrops no)
	)
	(paper "A4")
	(title_block
		(title "timecard-production-celestica-r4006 — R4006-B0001-02_R01.brd")
		(comment 1 "Time Appliance Project (Time Card) / footprints 159-160 of 1113")
	)
	(layers
		(0 "F.Cu" signal "TOP")
		(4 "In1.Cu" signal "L02_GND1")
		(6 "In2.Cu" signal "L03_SIG1")
		(8 "In3.Cu" signal "L04_GND2")
		(10 "In4.Cu" signal "L05_VCC1")
		(12 "In5.Cu" signal "L06_VCC2")
		(14 "In6.Cu" signal "L07_GND3")
		(16 "In7.Cu" signal "L08_SIG2")
		(18 "In8.Cu" signal "L09_GND4")
		(2 "B.Cu" signal "BOTTOM")
		(9 "F.Adhes" user "F.Adhesive")
		(11 "B.Adhes" user "B.Adhesive")
		(13 "F.Paste" user "Package Geometry/Pastemask Top")
		(15 "B.Paste" user "Package Geometry/Pastemask Bottom")
		(5 "F.SilkS" user "Ref Des/Silkscreen Top")
		(7 "B.SilkS" user "Ref Des/Silkscreen Bottom")
		(1 "F.Mask" user "Board Geometry/Soldermask Top")
		(3 "B.Mask" user "Board Geometry/Soldermask Bottom")
		(17 "Dwgs.User" user "User.Drawings")
		(19 "Cmts.User" user "User.Comments")
		(21 "Eco1.User" user "User.Eco1")
		(23 "Eco2.User" user "User.Eco2")
		(25 "Edge.Cuts" user "Board Geometry/Outline")
		(27 "Margin" user)
		(31 "F.CrtYd" user "Package Geometry/Place Bound Top")
		(29 "B.CrtYd" user "Package Geometry/Place Bound Bottom")
		(35 "F.Fab" user "Ref Des/Assembly Top")
		(33 "B.Fab" user "Ref Des/Assembly Bottom")
	)
	(footprint ""
		(layer "F.Cu")
		(at 102.997 -26.67 90)
		(property "Reference" "C253"
			(at 0.508 -2.24663 90)
			(unlocked yes)
			(layer "F.SilkS")
			(effects
				(font
					(size 0.7874 0.5842)
					(thickness 0.1524)
				)
			)
		)
		(property "Value" "VAL*"
			(at 0.0762 2.067306 90)
			(unlocked yes)
			(layer "F.Fab")
			(hide yes)
			(effects
				(font
					(size 0.7874 0.5842)
					(thickness 0.1524)
				)
			)
		)
		(property "Tolerance" "TOL*"
			(at 0.0762 3.032506 90)
			(unlocked yes)
			(layer "Cmts.User")
			(hide yes)
			(effects
				(font
					(size 0.7874 0.5842)
					(thickness 0.1524)
				)
			)
		)
		(property "User Part Number" "PARTNUM*"
			(at 0.1016 4.023106 90)
			(unlocked yes)
			(layer "Cmts.User")
			(hide yes)
			(effects
				(font
					(size 0.7874 0.5842)
					(thickness 0.1524)
				)
			)
		)
		(property "Device Type" "CAPACITOR-G105-0B104-CK,0.1UF,A"
			(at 0.0508 1.127506 90)
			(unlocked yes)
			(layer "F.Fab")
			(hide yes)
			(effects
				(font
					(size 0.7874 0.5842)
					(thickness 0.1524)
				)
			)
		)
		(duplicate_pad_numbers_are_jumpers no)
		(fp_line
			(start 1.143 -0.5588)
			(end -1.143 -0.5588)
			(stroke
				(width 0.1)
				(type default)
			)
			(layer "F.SilkS")
		)
		(fp_line
			(start -1.143 -0.5588)
			(end -1.143 0.5588)
			(stroke
				(width 0.1)
				(type default)
			)
			(layer "F.SilkS")
		)
		(fp_line
			(start 1.143 0.5588)
			(end 1.143 -0.5588)
			(stroke
				(width 0.1)
				(type default)
			)
			(layer "F.SilkS")
		)
		(fp_line
			(start -1.143 0.5588)
			(end 1.143 0.5588)
			(stroke
				(width 0.1)
				(type default)
			)
			(layer "F.SilkS")
		)
		(fp_rect
			(start -1.143 -0.5588)
			(end 1.143 0.5588)
			(stroke
				(width 0)
				(type default)
			)
			(fill no)
			(layer "F.CrtYd")
		)
		(fp_line
			(start 0.508 -0.3048)
			(end -0.508 -0.3048)
			(stroke
				(width 0.1)
				(type default)
			)
			(layer "F.Fab")
		)
		(fp_line
			(start -0.508 -0.3048)
			(end -0.508 0.3048)
			(stroke
				(width 0.1)
				(type default)
			)
			(layer "F.Fab")
		)
		(fp_line
			(start 0.508 0.3048)
			(end 0.508 -0.3048)
			(stroke
				(width 0.1)
				(type default)
			)
			(layer "F.Fab")
		)
		(fp_line
			(start -0.508 0.3048)
			(end 0.508 0.3048)
			(stroke
				(width 0.1)
				(type default)
			)
			(layer "F.Fab")
		)
		(pad "1" smd rect
			(at -0.5334 0 90)
			(size 0.7112 0.6096)
			(layers "F.Cu" "F.Mask" "F.Paste")
			(net "OSC_125M_CLKP")
		)
		(pad "2" smd rect
			(at 0.5334 0 90)
			(size 0.7112 0.6096)
			(layers "F.Cu" "F.Mask" "F.Paste")
			(net "MHZ125CLKP_CLKIN")
		)
		(zone
			(layer "F.Cu")
			(hatch none 0.5)
			(connect_pads
				(clearance 0)
			)
			(min_thickness 0.25)
			(keepout
				(tracks allowed)
				(vias not_allowed)
				(pads allowed)
				(copperpour not_allowed)
				(footprints allowed)
			)
			(placement
				(enabled no)
				(sheetname "")
			)
			(fill
				(thermal_gap 0.5)
				(thermal_bridge_width 0.5)
				(island_removal_mode 0)
			)
			(polygon
				(pts
					(xy 102.6922 -26.5938) (xy 103.3018 -26.5938) (xy 103.3018 -26.7462) (xy 102.6922 -26.7462)
				)
			)
		)
	)
	(footprint ""
		(layer "F.Cu")
		(at 12.827 -28.06446 90)
		(property "Reference" "R377"
			(at -0.50546 -2.37363 90)
			(unlocked yes)
			(layer "F.SilkS")
			(effects
				(font
					(size 0.7874 0.5842)
					(thickness 0.1524)
				)
			)
		)
		(property "Value" "VAL*"
			(at 0.02032 2.13233 90)
			(unlocked yes)
			(layer "F.Fab")
			(hide yes)
			(effects
				(font
					(size 0.7874 0.5842)
					(thickness 0.1524)
				)
			)
		)
		(property "Tolerance" "TOL*"
			(at 0.044704 3.05435 90)
			(unlocked yes)
			(layer "Cmts.User")
			(hide yes)
			(effects
				(font
					(size 0.7874 0.5842)
					(thickness 0.1524)
				)
			)
		)
		(property "User Part Number" "PARTNUM*"
			(at 0.02032 4.024884 90)
			(unlocked yes)
			(layer "Cmts.User")
			(hide yes)
			(effects
				(font
					(size 0.7874 0.5842)
					(thickness 0.1524)
				)
			)
		)
		(property "Device Type" "RESISTOR-G155-14701-01,4.7KOHMA"
			(at 0.008382 1.210564 90)
			(unlocked yes)
			(layer "F.Fab")
			(hide yes)
			(effects
				(font
					(size 0.7874 0.5842)
					(thickness 0.1524)
				)
			)
		)
		(duplicate_pad_numbers_are_jumpers no)
		(fp_line
			(start 1.143 -0.5588)
			(end -1.143 -0.5588)
			(stroke
				(width 0.1)
				(type default)
			)
			(layer "F.SilkS")
		)
		(fp_line
			(start -1.143 -0.5588)
			(end -1.143 0.5588)
			(stroke
				(width 0.1)
				(type default)
			)
			(layer "F.SilkS")
		)
		(fp_line
			(start 1.143 0.5588)
			(end 1.143 -0.5588)
			(stroke
				(width 0.1)
				(type default)
			)
			(layer "F.SilkS")
		)
		(fp_line
			(start -1.143 0.5588)
			(end 1.143 0.5588)
			(stroke
				(width 0.1)
				(type default)
			)
			(layer "F.SilkS")
		)
		(fp_rect
			(start 1.143 0.5588)
			(end -1.143 -0.5588)
			(stroke
				(width 0)
				(type default)
			)
			(fill no)
			(layer "F.CrtYd")
		)
		(fp_line
			(start 0.508 -0.3048)
			(end -0.508 -0.3048)
			(stroke
				(width 0.1)
				(type default)
			)
			(layer "F.Fab")
		)
		(fp_line
			(start -0.508 -0.3048)
			(end -0.508 0.3048)
			(stroke
				(width 0.1)
				(type default)
			)
			(layer "F.Fab")
		)
		(fp_line
			(start 0.508 0.3048)
			(end 0.508 -0.3048)
			(stroke
				(width 0.1)
				(type default)
			)
			(layer "F.Fab")
		)
		(fp_line
			(start -0.508 0.3048)
			(end 0.508 0.3048)
			(stroke
				(width 0.1)
				(type default)
			)
			(layer "F.Fab")
		)
		(pad "1" smd rect
			(at -0.5334 0 90)
			(size 0.7112 0.6096)
			(layers "F.Cu" "F.Mask" "F.Paste")
			(net "XP3R3V_FPGA")
		)
		(pad "2" smd rect
			(at 0.5334 0 90)
			(size 0.7112 0.6096)
			(layers "F.Cu" "F.Mask" "F.Paste")
			(net "SMA3_SIG_IN_BF_EN_N")
		)
		(zone
			(layer "F.Cu")
			(hatch none 0.5)
			(connect_pads
				(clearance 0)
			)
			(min_thickness 0.25)
			(keepout
				(tracks not_allowed)
				(vias allowed)
				(pads allowed)
				(copperpour not_allowed)
				(footprints allowed)
			)
			(placement
				(enabled no)
				(sheetname "")
			)
			(fill
				(thermal_gap 0.5)
				(thermal_bridge_width 0.5)
				(island_removal_mode 0)
			)
			(polygon
				(pts
					(xy 13.1318 -28.14066) (xy 12.5222 -28.14066) (xy 12.5222 -27.98826) (xy 13.1318 -27.98826)
				)
			)
		)
		(zone
			(layer "F.Cu")
			(hatch none 0.5)
			(connect_pads
				(clearance 0)
			)
			(min_thickness 0.25)
			(keepout
				(tracks allowed)
				(vias not_allowed)
				(pads allowed)
				(copperpour not_allowed)
				(footprints allowed)
			)
			(placement
				(enabled no)
				(sheetname "")
			)
			(fill
				(thermal_gap 0.5)
				(thermal_bridge_width 0.5)
				(island_removal_mode 0)
			)
			(polygon
				(pts
					(xy 13.1318 -28.14066) (xy 12.5222 -28.14066) (xy 12.5222 -27.98826) (xy 13.1318 -27.98826)
				)
			)
		)
	)
)
